(kicad_pcb
	(version 20260206)
	(generator "pcbnew")
	(generator_version "10.0")
	(general
		(thickness 1.6)
		(legacy_teardrops no)
	)
	(paper "A4")
	(title_block
		(title "v1-chassis-manager — T6M_CM_d_v01_1031_1645.brd")
		(comment 1 "Open CloudServer (Microsoft) / footprints 102-104 of 2512")
	)
	(layers
		(0 "F.Cu" signal "TOP")
		(4 "In1.Cu" signal "GND1")
		(6 "In2.Cu" signal "IN1")
		(8 "In3.Cu" signal "VCC1")
		(10 "In4.Cu" signal "VCC2")
		(12 "In5.Cu" signal "GND2")
		(14 "In6.Cu" signal "IN2")
		(16 "In7.Cu" signal "IN3")
		(18 "In8.Cu" signal "GND3")
		(2 "B.Cu" signal "BOTTOM")
		(9 "F.Adhes" user "F.Adhesive")
		(11 "B.Adhes" user "B.Adhesive")
		(13 "F.Paste" user "Package Geometry/Pastemask Top")
		(15 "B.Paste" user "Package Geometry/Pastemask Bottom")
		(5 "F.SilkS" user "Ref Des/Silkscreen Top")
		(7 "B.SilkS" user "Ref Des/Silkscreen Bottom")
		(1 "F.Mask" user "Board Geometry/Soldermask Top")
		(3 "B.Mask" user "Board Geometry/Soldermask Bottom")
		(17 "Dwgs.User" user "User.Drawings")
		(19 "Cmts.User" user "User.Comments")
		(21 "Eco1.User" user "User.Eco1")
		(23 "Eco2.User" user "User.Eco2")
		(25 "Edge.Cuts" user "Board Geometry/Outline")
		(27 "Margin" user)
		(31 "F.CrtYd" user "Package Geometry/Place Bound Top")
		(29 "B.CrtYd" user "Package Geometry/Place Bound Bottom")
		(35 "F.Fab" user "Ref Des/Assembly Top")
		(33 "B.Fab" user "Ref Des/Assembly Bottom")
	)
	(footprint ""
		(layer "F.Cu")
		(at 74.53376 -188.126624 90)
		(property "Reference" "C704"
			(at 4.548886 -1.165098 90)
			(unlocked yes)
			(layer "F.SilkS")
			(effects
				(font
					(size 0.7874 0.5842)
					(thickness 0.1524)
				)
				(justify left)
			)
		)
		(property "Value" ""
			(at 0 0 90)
			(layer "F.Fab")
			(effects
				(font
					(size 1.27 1.27)
				)
			)
		)
		(duplicate_pad_numbers_are_jumpers no)
		(fp_line
			(start 0.7874 -0.4064)
			(end 0.7874 0.4064)
			(stroke
				(width 0.1524)
				(type default)
			)
			(layer "F.SilkS")
		)
		(fp_line
			(start -0.7874 -0.4064)
			(end 0.7874 -0.4064)
			(stroke
				(width 0.1524)
				(type default)
			)
			(layer "F.SilkS")
		)
		(fp_line
			(start 0 0.381)
			(end 0 -0.381)
			(stroke
				(width 0.1524)
				(type default)
			)
			(layer "F.SilkS")
		)
		(fp_line
			(start 0.7874 0.4064)
			(end -0.7874 0.4064)
			(stroke
				(width 0.1524)
				(type default)
			)
			(layer "F.SilkS")
		)
		(fp_line
			(start -0.7874 0.4064)
			(end -0.7874 -0.4064)
			(stroke
				(width 0.1524)
				(type default)
			)
			(layer "F.SilkS")
		)
		(fp_poly
			(pts
				(xy -0.5334 0.254) (xy -0.635 0.254) (xy -0.635 0.2286) (xy -0.635 -0.254) (xy -0.5334 -0.254) (xy -0.5334 -0.2794)
				(xy 0.5334 -0.2794) (xy 0.5334 -0.254) (xy 0.635 -0.254) (xy 0.635 0.254) (xy 0.5334 0.254) (xy 0.5334 0.2794)
				(xy -0.508 0.2794) (xy -0.5334 0.2794)
			)
			(stroke
				(width 0)
				(type default)
			)
			(fill no)
			(layer "F.CrtYd")
		)
		(pad "1" smd rect
			(at 0.40005 0 90)
			(size 0.4572 0.508)
			(layers "F.Cu" "F.Mask" "F.Paste")
			(net "UART_T4_NODE2_TXD_R")
		)
		(pad "2" smd rect
			(at -0.40005 0 90)
			(size 0.4572 0.508)
			(layers "F.Cu" "F.Mask" "F.Paste")
			(net "GND")
		)
	)
	(footprint ""
		(layer "F.Cu")
		(at 79.99476 -182.411624 -90)
		(property "Reference" "C585"
			(at 1.297178 1.584198 90)
			(unlocked yes)
			(layer "F.SilkS")
			(effects
				(font
					(size 0.7874 0.5842)
					(thickness 0.1524)
				)
				(justify left)
			)
		)
		(property "Value" ""
			(at 0 0 270)
			(layer "F.Fab")
			(effects
				(font
					(size 1.27 1.27)
				)
			)
		)
		(duplicate_pad_numbers_are_jumpers no)
		(fp_line
			(start -0.7874 0.4064)
			(end -0.7874 -0.4064)
			(stroke
				(width 0.1524)
				(type default)
			)
			(layer "F.SilkS")
		)
		(fp_line
			(start 0.7874 0.4064)
			(end -0.7874 0.4064)
			(stroke
				(width 0.1524)
				(type default)
			)
			(layer "F.SilkS")
		)
		(fp_line
			(start 0 0.381)
			(end 0 -0.381)
			(stroke
				(width 0.1524)
				(type default)
			)
			(layer "F.SilkS")
		)
		(fp_line
			(start -0.7874 -0.4064)
			(end 0.7874 -0.4064)
			(stroke
				(width 0.1524)
				(type default)
			)
			(layer "F.SilkS")
		)
		(fp_line
			(start 0.7874 -0.4064)
			(end 0.7874 0.4064)
			(stroke
				(width 0.1524)
				(type default)
			)
			(layer "F.SilkS")
		)
		(fp_poly
			(pts
				(xy -0.5334 0.254) (xy -0.635 0.254) (xy -0.635 0.2286) (xy -0.635 -0.254) (xy -0.5334 -0.254) (xy -0.5334 -0.2794)
				(xy 0.5334 -0.2794) (xy 0.5334 -0.254) (xy 0.635 -0.254) (xy 0.635 0.254) (xy 0.5334 0.254) (xy 0.5334 0.2794)
				(xy -0.508 0.2794) (xy -0.5334 0.2794)
			)
			(stroke
				(width 0)
				(type default)
			)
			(fill no)
			(layer "F.CrtYd")
		)
		(pad "1" smd rect
			(at 0.40005 0 270)
			(size 0.4572 0.508)
			(layers "F.Cu" "F.Mask" "F.Paste")
			(net "P3V3_NODE1")
		)
		(pad "2" smd rect
			(at -0.40005 0 270)
			(size 0.4572 0.508)
			(layers "F.Cu" "F.Mask" "F.Paste")
			(net "GND")
		)
	)
	(footprint ""
		(layer "F.Cu")
		(at 151.732234 -8.585962 180)
		(property "Reference" "J26"
			(at 1.646682 3.350768 0)
			(unlocked yes)
			(layer "F.SilkS")
			(effects
				(font
					(size 0.7874 0.5842)
					(thickness 0.1524)
				)
				(justify left)
			)
		)
		(property "Value" ""
			(at 0 0 180)
			(layer "F.Fab")
			(effects
				(font
					(size 1.27 1.27)
				)
			)
		)
		(duplicate_pad_numbers_are_jumpers no)
		(fp_line
			(start 6.599936 2.640076)
			(end -6.599936 2.640076)
			(stroke
				(width 0.1524)
				(type default)
			)
			(layer "F.SilkS")
		)
		(fp_line
			(start 6.599936 -2.640076)
			(end 6.599936 2.640076)
			(stroke
				(width 0.1524)
				(type default)
			)
			(layer "F.SilkS")
		)
		(fp_line
			(start -6.599936 2.640076)
			(end -6.599936 -2.640076)
			(stroke
				(width 0.1524)
				(type default)
			)
			(layer "F.SilkS")
		)
		(fp_line
			(start -6.599936 -2.640076)
			(end 6.599936 -2.640076)
			(stroke
				(width 0.1524)
				(type default)
			)
			(layer "F.SilkS")
		)
		(fp_poly
			(pts
				(xy -5.196586 3.444494) (xy -5.958586 5.349494) (xy -4.434586 5.349494)
			)
			(stroke
				(width 0)
				(type default)
			)
			(fill yes)
			(layer "F.SilkS")
		)
		(fp_poly
			(pts
				(xy -5.969 -2.159) (xy 5.969 -2.159) (xy 5.969 2.159) (xy -5.969 2.159)
			)
			(stroke
				(width 0)
				(type default)
			)
			(fill no)
			(layer "B.CrtYd")
		)
		(fp_poly
			(pts
				(xy -6.599936 2.640076) (xy 6.599936 2.640076) (xy 6.599936 -2.640076) (xy -6.599936 -2.640076)
			)
			(stroke
				(width 0)
				(type default)
			)
			(fill no)
			(layer "F.CrtYd")
		)
		(fp_line
			(start 6.599936 2.640076)
			(end -6.599936 2.640076)
			(stroke
				(width 0.1)
				(type default)
			)
			(layer "F.Fab")
		)
		(fp_line
			(start 6.599936 -2.640076)
			(end 6.599936 2.640076)
			(stroke
				(width 0.1)
				(type default)
			)
			(layer "F.Fab")
		)
		(fp_line
			(start -6.599936 2.640076)
			(end -6.599936 -2.640076)
			(stroke
				(width 0.1)
				(type default)
			)
			(layer "F.Fab")
		)
		(fp_line
			(start -6.599936 -2.640076)
			(end 6.599936 -2.640076)
			(stroke
				(width 0.1)
				(type default)
			)
			(layer "F.Fab")
		)
		(fp_poly
			(pts
				(xy -7.4295 1.27) (xy -9.3345 0.508) (xy -9.3345 2.032)
			)
			(stroke
				(width 0)
				(type default)
			)
			(fill yes)
			(layer "F.Fab")
		)
		(fp_text user "9"
			(at 7.405624 2.211324 0)
			(unlocked yes)
			(layer "F.SilkS")
			(effects
				(font
					(size 0.7874 0.5842)
					(thickness 0.1524)
				)
				(justify left)
			)
		)
		(fp_text user "10"
			(at 6.613144 -3.49377 0)
			(unlocked yes)
			(layer "F.SilkS")
			(effects
				(font
					(size 0.7874 0.5842)
					(thickness 0.1524)
				)
				(justify left)
			)
		)
		(fp_text user "2"
			(at -5.792216 -3.447796 0)
			(unlocked yes)
			(layer "F.SilkS")
			(effects
				(font
					(size 0.7874 0.5842)
					(thickness 0.1524)
				)
				(justify left)
			)
		)
		(fp_text user "1"
			(at -6.914896 2.450084 0)
			(unlocked yes)
			(layer "F.SilkS")
			(effects
				(font
					(size 0.7874 0.5842)
					(thickness 0.1524)
				)
				(justify left)
			)
		)
		(fp_text user "9"
			(at 6.305042 1.09982 0)
			(unlocked yes)
			(layer "B.SilkS")
			(effects
				(font
					(size 0.7874 0.5842)
					(thickness 0.1524)
				)
				(justify left mirror)
			)
		)
		(fp_text user "10"
			(at 6.142482 -1.373632 0)
			(unlocked yes)
			(layer "B.SilkS")
			(effects
				(font
					(size 0.7874 0.5842)
					(thickness 0.1524)
				)
				(justify left mirror)
			)
		)
		(fp_text user "1"
			(at -6.679438 1.100074 0)
			(unlocked yes)
			(layer "B.SilkS")
			(effects
				(font
					(size 0.7874 0.5842)
					(thickness 0.1524)
				)
				(justify left mirror)
			)
		)
		(fp_text user "2"
			(at -6.679438 -1.275842 0)
			(unlocked yes)
			(layer "B.SilkS")
			(effects
				(font
					(size 0.7874 0.5842)
					(thickness 0.1524)
				)
				(justify left mirror)
			)
		)
		(fp_text user "10"
			(at 7.5438 -1.361948 180)
			(unlocked yes)
			(layer "B.Fab")
			(effects
				(font
					(size 0.7874 0.5842)
					(thickness 0.000001)
				)
				(justify left mirror)
			)
		)
		(fp_text user "9"
			(at 7.1501 1.178052 180)
			(unlocked yes)
			(layer "B.Fab")
			(effects
				(font
					(size 0.7874 0.5842)
					(thickness 0.000001)
				)
				(justify left mirror)
			)
		)
		(fp_text user "1"
			(at -6.1849 1.178052 180)
			(unlocked yes)
			(layer "B.Fab")
			(effects
				(font
					(size 0.7874 0.5842)
					(thickness 0.000001)
				)
				(justify left mirror)
			)
		)
		(fp_text user "2"
			(at -6.1849 -1.361948 180)
			(unlocked yes)
			(layer "B.Fab")
			(effects
				(font
					(size 0.7874 0.5842)
					(thickness 0.000001)
				)
				(justify left mirror)
			)
		)
		(fp_text user "9"
			(at 6.9469 1.178052 180)
			(unlocked yes)
			(layer "F.Fab")
			(effects
				(font
					(size 0.7874 0.5842)
					(thickness 0.000001)
				)
				(justify left)
			)
		)
		(fp_text user "10"
			(at 6.5532 -1.361948 180)
			(unlocked yes)
			(layer "F.Fab")
			(effects
				(font
					(size 0.7874 0.5842)
					(thickness 0.000001)
				)
				(justify left)
			)
		)
		(fp_text user "1"
			(at -7.5311 1.178052 180)
			(unlocked yes)
			(layer "F.Fab")
			(effects
				(font
					(size 0.7874 0.5842)
					(thickness 0.000001)
				)
				(justify left)
			)
		)
		(fp_text user "2"
			(at -7.5311 -1.361948 180)
			(unlocked yes)
			(layer "F.Fab")
			(effects
				(font
					(size 0.7874 0.5842)
					(thickness 0.000001)
				)
				(justify left)
			)
		)
		(pad "1" thru_hole rect
			(at -5.08 1.27 270)
			(size 1.6764 1.6764)
			(drill 1.1684)
			(layers "*.Cu" "*.Mask")
			(remove_unused_layers no)
			(net "JTAG_CPLD2_TCK")
			(clearance 0)
			(padstack
				(mode front_inner_back)
				(layer "Inner"
					(shape circle)
					(size 1.6764 1.6764)
					(clearance 0)
				)
				(layer "B.Cu"
					(shape rect)
					(size 1.6764 1.6764)
					(clearance 0)
				)
			)
		)
		(pad "2" thru_hole circle
			(at -5.08 -1.27 270)
			(size 1.6764 1.6764)
			(drill 1.1684)
			(layers "*.Cu" "*.Mask")
			(remove_unused_layers no)
			(net "GND")
			(clearance 0)
		)
		(pad "3" thru_hole circle
			(at -2.54 1.27 270)
			(size 1.6764 1.6764)
			(drill 1.1684)
			(layers "*.Cu" "*.Mask")
			(remove_unused_layers no)
			(net "JTAG_CPLD2_TDO")
			(clearance 0)
		)
		(pad "4" thru_hole circle
			(at -2.54 -1.27 270)
			(size 1.6764 1.6764)
			(drill 1.1684)
			(layers "*.Cu" "*.Mask")
			(remove_unused_layers no)
			(net "P3V3_NODE1")
			(clearance 0)
		)
		(pad "5" thru_hole circle
			(at 0 1.27 270)
			(size 1.6764 1.6764)
			(drill 1.1684)
			(layers "*.Cu" "*.Mask")
			(remove_unused_layers no)
			(net "JTAG_CPLD2_TMS")
			(clearance 0)
		)
		(pad "6" thru_hole circle
			(at 0 -1.27 270)
			(size 1.6764 1.6764)
			(drill 1.1684)
			(layers "*.Cu" "*.Mask")
			(remove_unused_layers no)
			(net "Net_2262")
			(clearance 0)
		)
		(pad "7" thru_hole circle
			(at 2.54 1.27 270)
			(size 1.6764 1.6764)
			(drill 1.1684)
			(layers "*.Cu" "*.Mask")
			(remove_unused_layers no)
			(net "Net_2261")
			(clearance 0)
		)
		(pad "8" thru_hole circle
			(at 2.54 -1.27 270)
			(size 1.6764 1.6764)
			(drill 1.1684)
			(layers "*.Cu" "*.Mask")
			(remove_unused_layers no)
			(net "Net_2260")
			(clearance 0)
		)
		(pad "9" thru_hole circle
			(at 5.08 1.27 270)
			(size 1.6764 1.6764)
			(drill 1.1684)
			(layers "*.Cu" "*.Mask")
			(remove_unused_layers no)
			(net "JTAG_CPLD2_TDI")
			(clearance 0)
		)
		(pad "10" thru_hole circle
			(at 5.08 -1.27 270)
			(size 1.6764 1.6764)
			(drill 1.1684)
			(layers "*.Cu" "*.Mask")
			(remove_unused_layers no)
			(net "GND")
			(clearance 0)
		)
	)
)
